# T6G (Grand Teton) — schematic netlist excerpt (pin names and nets, part order shuffled) for the footprints in the layout excerpt that follows; sources: Cadence DE-HDL packaged netlist, KiCad conversion of 04192023_DAF0TMB3IC0_F0TG_MB_C_brd_V02_OCP.brd

PPQ1  MOSFET_NCH_1D3S  PSMNR58-30YLH IC  pkg SOT1023  page 266
  \1\  = P12V_AUX
  \2\  = P12V_AUX
  \3\  = P12V_AUX
  \4\  = P12V_HSC_GATE_G5
  \5\  = P12V_MAIN_R

PC6611_1  Q_CAP  100NF 50V 10% X7R  pkg C0402  page 365 : A = PV09_RETIMER_CPU1_VCCS ; B = GND
H94  HOLE  EMPTY  pkg TH  page 230 : \1\ = GND

(kicad_pcb
	(version 20260206)
	(generator "pcbnew")
	(generator_version "10.0")
	(general
		(thickness 1.6)
		(legacy_teardrops no)
	)
	(paper "A4")
	(title_block
		(title "04192023_DAF0TMB3IC0_F0TG_MB_C_brd_V02_OCP.brd")
		(comment 1 "Grand Teton / footprints 4452-4454 of 8354")
	)
	(layers
		(0 "F.Cu" signal "TOP")
		(4 "In1.Cu" signal "GND")
		(6 "In2.Cu" signal "IN1")
		(8 "In3.Cu" signal "GND1")
		(10 "In4.Cu" signal "IN2")
		(12 "In5.Cu" signal "GND2")
		(14 "In6.Cu" signal "IN3")
		(16 "In7.Cu" signal "GND3")
		(18 "In8.Cu" signal "VCC")
		(20 "In9.Cu" signal "VCC1")
		(22 "In10.Cu" signal "GND4")
		(24 "In11.Cu" signal "IN4")
		(26 "In12.Cu" signal "GND5")
		(28 "In13.Cu" signal "IN5")
		(30 "In14.Cu" signal "GND6")
		(32 "In15.Cu" signal "IN6")
		(34 "In16.Cu" signal "GND7")
		(2 "B.Cu" signal "BOTTOM")
		(9 "F.Adhes" user "F.Adhesive")
		(11 "B.Adhes" user "B.Adhesive")
		(13 "F.Paste" user "Package Geometry/Pastemask Top")
		(15 "B.Paste" user "Package Geometry/Pastemask Bottom")
		(5 "F.SilkS" user "Ref Des/Silkscreen Top")
		(7 "B.SilkS" user "Ref Des/Silkscreen Bottom")
		(1 "F.Mask" user "Board Geometry/Soldermask Top")
		(3 "B.Mask" user "Board Geometry/Soldermask Bottom")
		(17 "Dwgs.User" user "User.Drawings")
		(19 "Cmts.User" user "User.Comments")
		(21 "Eco1.User" user "User.Eco1")
		(23 "Eco2.User" user "User.Eco2")
		(25 "Edge.Cuts" user "Board Geometry/Outline")
		(27 "Margin" user)
		(31 "F.CrtYd" user "Package Geometry/Place Bound Top")
		(29 "B.CrtYd" user "Package Geometry/Place Bound Bottom")
		(35 "F.Fab" user "Ref Des/Assembly Top")
		(33 "B.Fab" user "Ref Des/Assembly Bottom")
	)
	(footprint ""
		(layer "F.Cu")
		(at 241.656108 -385.27736 90)
		(property "Reference" "PPQ1"
			(at -1.930908 -3.4417 90)
			(unlocked yes)
			(layer "F.SilkS")
			(effects
				(font
					(size 0.7874 0.5842)
					(thickness 0.1524)
				)
				(justify left)
			)
		)
		(property "Value" ""
			(at 0 0 90)
			(layer "F.Fab")
			(effects
				(font
					(size 1.27 1.27)
				)
			)
		)
		(duplicate_pad_numbers_are_jumpers no)
		(fp_line
			(start 2.350008 -2.649982)
			(end 2.350008 -2.4892)
			(stroke
				(width 0.1524)
				(type default)
			)
			(layer "F.SilkS")
		)
		(fp_line
			(start -2.350008 -2.649982)
			(end 2.350008 -2.649982)
			(stroke
				(width 0.1524)
				(type default)
			)
			(layer "F.SilkS")
		)
		(fp_line
			(start -2.350008 -2.4384)
			(end -2.350008 -2.649982)
			(stroke
				(width 0.1524)
				(type default)
			)
			(layer "F.SilkS")
		)
		(fp_line
			(start 2.350008 2.4892)
			(end 2.350008 2.649982)
			(stroke
				(width 0.1524)
				(type default)
			)
			(layer "F.SilkS")
		)
		(fp_line
			(start 2.350008 2.649982)
			(end -2.350008 2.649982)
			(stroke
				(width 0.1524)
				(type default)
			)
			(layer "F.SilkS")
		)
		(fp_line
			(start -2.350008 2.649982)
			(end -2.350008 2.413)
			(stroke
				(width 0.1524)
				(type default)
			)
			(layer "F.SilkS")
		)
		(fp_poly
			(pts
				(xy -3.28803 -4.262628) (xy -2.492502 -4.177538) (xy -3.02006 -3.186684)
			)
			(stroke
				(width 0)
				(type default)
			)
			(fill yes)
			(layer "F.SilkS")
		)
		(fp_line
			(start 2.350008 -2.649982)
			(end 2.350008 2.649982)
			(stroke
				(width 0.1)
				(type default)
			)
			(layer "F.Fab")
		)
		(fp_line
			(start -2.350008 -2.649982)
			(end 2.350008 -2.649982)
			(stroke
				(width 0.1)
				(type default)
			)
			(layer "F.Fab")
		)
		(fp_line
			(start 2.350008 2.649982)
			(end -2.350008 2.649982)
			(stroke
				(width 0.1)
				(type default)
			)
			(layer "F.Fab")
		)
		(fp_line
			(start -2.350008 2.649982)
			(end -2.350008 -2.649982)
			(stroke
				(width 0.1)
				(type default)
			)
			(layer "F.Fab")
		)
		(fp_poly
			(pts
				(xy -3.717544 -1.905) (xy -4.758944 -2.3241) (xy -4.758944 -1.524)
			)
			(stroke
				(width 0)
				(type default)
			)
			(fill yes)
			(layer "F.Fab")
		)
		(pad "1" smd rect
			(at -2.999994 -1.905)
			(size 0.7112 1.1684)
			(layers "F.Cu" "F.Mask" "F.Paste")
			(net "P12V_AUX")
		)
		(pad "2" smd rect
			(at -2.999994 -0.635)
			(size 0.7112 1.1684)
			(layers "F.Cu" "F.Mask" "F.Paste")
			(net "P12V_AUX")
		)
		(pad "3" smd rect
			(at -2.999994 0.635)
			(size 0.7112 1.1684)
			(layers "F.Cu" "F.Mask" "F.Paste")
			(net "P12V_AUX")
		)
		(pad "4" smd rect
			(at -2.999994 1.905)
			(size 0.7112 1.1684)
			(layers "F.Cu" "F.Mask" "F.Paste")
			(net "P12V_HSC_GATE_G5")
		)
		(pad "5" smd circle
			(at 0.925068 0)
			(size 0 0)
			(layers "F.Cu" "F.Mask" "F.Paste")
			(net "P12V_MAIN_R")
		)
		(zone
			(layer "F.Cu")
			(hatch none 0.5)
			(connect_pads
				(clearance 0)
			)
			(min_thickness 0.25)
			(keepout
				(tracks not_allowed)
				(vias allowed)
				(pads allowed)
				(copperpour not_allowed)
				(footprints allowed)
			)
			(placement
				(enabled no)
				(sheetname "")
			)
			(fill
				(thermal_gap 0.5)
				(thermal_bridge_width 0.5)
				(island_removal_mode 0)
			)
			(polygon
				(pts
					(xy 239.014508 -383.7178) (xy 244.297708 -383.7178) (xy 244.297708 -382.92786) (xy 239.014508 -382.92786)
				)
			)
		)
	)
	(footprint ""
		(layer "F.Cu")
		(at 13.206984 -394.447268 90)
		(property "Reference" "PC6611_1"
			(at 0 0 90)
			(layer "F.SilkS")
			(hide yes)
			(effects
				(font
					(size 1.27 1.27)
				)
			)
		)
		(property "Value" ""
			(at 0 0 90)
			(layer "F.Fab")
			(effects
				(font
					(size 1.27 1.27)
				)
			)
		)
		(duplicate_pad_numbers_are_jumpers no)
		(fp_line
			(start 0.7874 -0.4064)
			(end 0.7874 0.4064)
			(stroke
				(width 0.1524)
				(type default)
			)
			(layer "F.SilkS")
		)
		(fp_line
			(start -0.7874 -0.4064)
			(end 0.7874 -0.4064)
			(stroke
				(width 0.1524)
				(type default)
			)
			(layer "F.SilkS")
		)
		(fp_line
			(start 0.7874 0.4064)
			(end -0.7874 0.4064)
			(stroke
				(width 0.1524)
				(type default)
			)
			(layer "F.SilkS")
		)
		(fp_line
			(start -0.7874 0.4064)
			(end -0.7874 -0.4064)
			(stroke
				(width 0.1524)
				(type default)
			)
			(layer "F.SilkS")
		)
		(fp_line
			(start -0.12065 -0.305054)
			(end -0.12065 -0.2794)
			(stroke
				(width 0.1)
				(type default)
			)
			(layer "F.Fab")
		)
		(fp_line
			(start -0.67945 -0.305054)
			(end -0.12065 -0.305054)
			(stroke
				(width 0.1)
				(type default)
			)
			(layer "F.Fab")
		)
		(fp_line
			(start 0.67945 -0.3048)
			(end 0.67945 0.3048)
			(stroke
				(width 0.1)
				(type default)
			)
			(layer "F.Fab")
		)
		(fp_line
			(start 0.12065 -0.3048)
			(end 0.67945 -0.3048)
			(stroke
				(width 0.1)
				(type default)
			)
			(layer "F.Fab")
		)
		(fp_line
			(start 0.12065 -0.2794)
			(end 0.12065 -0.3048)
			(stroke
				(width 0.1)
				(type default)
			)
			(layer "F.Fab")
		)
		(fp_line
			(start -0.12065 -0.2794)
			(end 0.12065 -0.2794)
			(stroke
				(width 0.1)
				(type default)
			)
			(layer "F.Fab")
		)
		(fp_line
			(start 0.120396 0.2794)
			(end -0.12065 0.2794)
			(stroke
				(width 0.1)
				(type default)
			)
			(layer "F.Fab")
		)
		(fp_line
			(start -0.12065 0.2794)
			(end -0.12065 0.3048)
			(stroke
				(width 0.1)
				(type default)
			)
			(layer "F.Fab")
		)
		(fp_line
			(start 0.67945 0.3048)
			(end 0.120396 0.3048)
			(stroke
				(width 0.1)
				(type default)
			)
			(layer "F.Fab")
		)
		(fp_line
			(start 0.120396 0.3048)
			(end 0.120396 0.2794)
			(stroke
				(width 0.1)
				(type default)
			)
			(layer "F.Fab")
		)
		(fp_line
			(start -0.12065 0.3048)
			(end -0.67945 0.3048)
			(stroke
				(width 0.1)
				(type default)
			)
			(layer "F.Fab")
		)
		(fp_line
			(start -0.67945 0.3048)
			(end -0.67945 -0.305054)
			(stroke
				(width 0.1)
				(type default)
			)
			(layer "F.Fab")
		)
		(pad "1" smd circle
			(at -0.40005 0 90)
			(size 0 0)
			(layers "F.Cu" "F.Mask" "F.Paste")
			(net "PV09_RETIMER_CPU1_VCCS")
		)
		(pad "2" smd circle
			(at 0.40005 0 90)
			(size 0 0)
			(layers "F.Cu" "F.Mask" "F.Paste")
			(net "GND")
		)
	)
	(footprint ""
		(layer "F.Cu")
		(at 100.500434 -435.59984)
		(property "Reference" "H94"
			(at -5.619242 -4.539742 0)
			(unlocked yes)
			(layer "F.SilkS")
			(effects
				(font
					(size 0.7874 0.5842)
					(thickness 0.1524)
				)
				(justify left)
			)
		)
		(property "Value" ""
			(at 0 0 0)
			(layer "F.Fab")
			(effects
				(font
					(size 1.27 1.27)
				)
			)
		)
		(duplicate_pad_numbers_are_jumpers no)
		(pad "1" thru_hole circle
			(at 0 0)
			(size 10.0076 10.0076)
			(drill 5.6134)
			(layers "*.Cu" "*.Mask")
			(remove_unused_layers no)
			(net "GND")
			(clearance -1.9431)
		)
	)
)
